# T6G (Grand Teton) — schematic netlist excerpt (pin names and nets, part order shuffled) for the footprints in the layout excerpt that follows; sources: Cadence DE-HDL packaged netlist, KiCad conversion of 04192023_DAF0TMB3IC0_F0TG_MB_C_brd_V02_OCP.brd

PR3846  Q_RES  1.33K 1% CHIP  pkg 0402LF  page 135 : A = GND ; B = P3V3_OCP_ILIMIT_1
PL72  Q_INDUCTOR  1.5UH IND  pkg SMLF  page 192 : \1\ = SW_PVDD_33_S5_SW ; \2\ = PVDD_33_S5
PC2144  Q_CAP  0.01UF 50V 10% EMPTY  pkg C0402  page 134 : A = P3V3_OCP_SFF_R ; B = P3V3_OCP_GATE_PU202_1

(kicad_pcb
	(version 20260206)
	(generator "pcbnew")
	(generator_version "10.0")
	(general
		(thickness 1.6)
		(legacy_teardrops no)
	)
	(paper "A4")
	(title_block
		(title "04192023_DAF0TMB3IC0_F0TG_MB_C_brd_V02_OCP.brd")
		(comment 1 "Grand Teton / footprints 2701-2703 of 8354")
	)
	(layers
		(0 "F.Cu" signal "TOP")
		(4 "In1.Cu" signal "GND")
		(6 "In2.Cu" signal "IN1")
		(8 "In3.Cu" signal "GND1")
		(10 "In4.Cu" signal "IN2")
		(12 "In5.Cu" signal "GND2")
		(14 "In6.Cu" signal "IN3")
		(16 "In7.Cu" signal "GND3")
		(18 "In8.Cu" signal "VCC")
		(20 "In9.Cu" signal "VCC1")
		(22 "In10.Cu" signal "GND4")
		(24 "In11.Cu" signal "IN4")
		(26 "In12.Cu" signal "GND5")
		(28 "In13.Cu" signal "IN5")
		(30 "In14.Cu" signal "GND6")
		(32 "In15.Cu" signal "IN6")
		(34 "In16.Cu" signal "GND7")
		(2 "B.Cu" signal "BOTTOM")
		(9 "F.Adhes" user "F.Adhesive")
		(11 "B.Adhes" user "B.Adhesive")
		(13 "F.Paste" user "Package Geometry/Pastemask Top")
		(15 "B.Paste" user "Package Geometry/Pastemask Bottom")
		(5 "F.SilkS" user "Ref Des/Silkscreen Top")
		(7 "B.SilkS" user "Ref Des/Silkscreen Bottom")
		(1 "F.Mask" user "Board Geometry/Soldermask Top")
		(3 "B.Mask" user "Board Geometry/Soldermask Bottom")
		(17 "Dwgs.User" user "User.Drawings")
		(19 "Cmts.User" user "User.Comments")
		(21 "Eco1.User" user "User.Eco1")
		(23 "Eco2.User" user "User.Eco2")
		(25 "Edge.Cuts" user "Board Geometry/Outline")
		(27 "Margin" user)
		(31 "F.CrtYd" user "Package Geometry/Place Bound Top")
		(29 "B.CrtYd" user "Package Geometry/Place Bound Bottom")
		(35 "F.Fab" user "Ref Des/Assembly Top")
		(33 "B.Fab" user "Ref Des/Assembly Bottom")
	)
	(footprint ""
		(layer "F.Cu")
		(at 419.76294 -101.270308 90)
		(property "Reference" "PR3846"
			(at 0 0 90)
			(layer "F.SilkS")
			(hide yes)
			(effects
				(font
					(size 1.27 1.27)
				)
			)
		)
		(property "Value" ""
			(at 0 0 90)
			(layer "F.Fab")
			(effects
				(font
					(size 1.27 1.27)
				)
			)
		)
		(duplicate_pad_numbers_are_jumpers no)
		(fp_line
			(start 0.7874 -0.4064)
			(end 0.7874 0.4064)
			(stroke
				(width 0.1524)
				(type default)
			)
			(layer "F.SilkS")
		)
		(fp_line
			(start -0.7874 -0.4064)
			(end 0.7874 -0.4064)
			(stroke
				(width 0.1524)
				(type default)
			)
			(layer "F.SilkS")
		)
		(fp_line
			(start 0.7874 0.4064)
			(end -0.7874 0.4064)
			(stroke
				(width 0.1524)
				(type default)
			)
			(layer "F.SilkS")
		)
		(fp_line
			(start -0.7874 0.4064)
			(end -0.7874 -0.4064)
			(stroke
				(width 0.1524)
				(type default)
			)
			(layer "F.SilkS")
		)
		(fp_line
			(start -0.12065 -0.305054)
			(end -0.12065 -0.2794)
			(stroke
				(width 0.1)
				(type default)
			)
			(layer "F.Fab")
		)
		(fp_line
			(start -0.67945 -0.305054)
			(end -0.12065 -0.305054)
			(stroke
				(width 0.1)
				(type default)
			)
			(layer "F.Fab")
		)
		(fp_line
			(start 0.67945 -0.3048)
			(end 0.67945 0.3048)
			(stroke
				(width 0.1)
				(type default)
			)
			(layer "F.Fab")
		)
		(fp_line
			(start 0.12065 -0.3048)
			(end 0.67945 -0.3048)
			(stroke
				(width 0.1)
				(type default)
			)
			(layer "F.Fab")
		)
		(fp_line
			(start 0.12065 -0.2794)
			(end 0.12065 -0.3048)
			(stroke
				(width 0.1)
				(type default)
			)
			(layer "F.Fab")
		)
		(fp_line
			(start -0.12065 -0.2794)
			(end 0.12065 -0.2794)
			(stroke
				(width 0.1)
				(type default)
			)
			(layer "F.Fab")
		)
		(fp_line
			(start 0.120396 0.2794)
			(end -0.12065 0.2794)
			(stroke
				(width 0.1)
				(type default)
			)
			(layer "F.Fab")
		)
		(fp_line
			(start -0.12065 0.2794)
			(end -0.12065 0.3048)
			(stroke
				(width 0.1)
				(type default)
			)
			(layer "F.Fab")
		)
		(fp_line
			(start 0.67945 0.3048)
			(end 0.120396 0.3048)
			(stroke
				(width 0.1)
				(type default)
			)
			(layer "F.Fab")
		)
		(fp_line
			(start 0.120396 0.3048)
			(end 0.120396 0.2794)
			(stroke
				(width 0.1)
				(type default)
			)
			(layer "F.Fab")
		)
		(fp_line
			(start -0.12065 0.3048)
			(end -0.67945 0.3048)
			(stroke
				(width 0.1)
				(type default)
			)
			(layer "F.Fab")
		)
		(fp_line
			(start -0.67945 0.3048)
			(end -0.67945 -0.305054)
			(stroke
				(width 0.1)
				(type default)
			)
			(layer "F.Fab")
		)
		(pad "1" smd circle
			(at -0.40005 0 90)
			(size 0 0)
			(layers "F.Cu" "F.Mask" "F.Paste")
			(net "GND")
		)
		(pad "2" smd circle
			(at 0.40005 0 90)
			(size 0 0)
			(layers "F.Cu" "F.Mask" "F.Paste")
			(net "P3V3_OCP_ILIMIT_1")
		)
	)
	(footprint ""
		(layer "F.Cu")
		(at 200.98512 -332.612238 -90)
		(property "Reference" "PL72"
			(at -0.763524 -4.20243 90)
			(unlocked yes)
			(layer "F.SilkS")
			(effects
				(font
					(size 0.7874 0.5842)
					(thickness 0.1524)
				)
				(justify left)
			)
		)
		(property "Value" ""
			(at 0 0 270)
			(layer "F.Fab")
			(effects
				(font
					(size 1.27 1.27)
				)
			)
		)
		(duplicate_pad_numbers_are_jumpers no)
		(fp_line
			(start -3.64998 3.350006)
			(end -3.64998 1.8288)
			(stroke
				(width 0.1524)
				(type default)
			)
			(layer "F.SilkS")
		)
		(fp_line
			(start 3.64998 3.350006)
			(end -3.64998 3.350006)
			(stroke
				(width 0.1524)
				(type default)
			)
			(layer "F.SilkS")
		)
		(fp_line
			(start 3.64998 1.8034)
			(end 3.64998 3.350006)
			(stroke
				(width 0.1524)
				(type default)
			)
			(layer "F.SilkS")
		)
		(fp_line
			(start -3.64998 -1.8034)
			(end -3.64998 -3.350006)
			(stroke
				(width 0.1524)
				(type default)
			)
			(layer "F.SilkS")
		)
		(fp_line
			(start -3.6576 -3.350006)
			(end 3.64998 -3.350006)
			(stroke
				(width 0.1524)
				(type default)
			)
			(layer "F.SilkS")
		)
		(fp_line
			(start 3.64998 -3.350006)
			(end 3.64998 -1.8034)
			(stroke
				(width 0.1524)
				(type default)
			)
			(layer "F.SilkS")
		)
		(fp_line
			(start -3.64998 3.350006)
			(end -3.64998 -3.350006)
			(stroke
				(width 0.1)
				(type default)
			)
			(layer "F.Fab")
		)
		(fp_line
			(start 3.64998 3.350006)
			(end -3.64998 3.350006)
			(stroke
				(width 0.1)
				(type default)
			)
			(layer "F.Fab")
		)
		(fp_line
			(start -3.64998 -3.350006)
			(end 3.64998 -3.350006)
			(stroke
				(width 0.1)
				(type default)
			)
			(layer "F.Fab")
		)
		(fp_line
			(start 3.64998 -3.350006)
			(end 3.64998 3.350006)
			(stroke
				(width 0.1)
				(type default)
			)
			(layer "F.Fab")
		)
		(pad "1" smd rect
			(at -2.92481 0 270)
			(size 2.15392 3.302)
			(layers "F.Cu" "F.Mask" "F.Paste")
			(net "SW_PVDD_33_S5_SW")
		)
		(pad "2" smd rect
			(at 2.92481 0 270)
			(size 2.15392 3.302)
			(layers "F.Cu" "F.Mask" "F.Paste")
			(net "PVDD_33_S5")
		)
	)
	(footprint ""
		(layer "F.Cu")
		(at 435.621176 -103.77043 90)
		(property "Reference" "PC2144"
			(at 0 0 90)
			(layer "F.SilkS")
			(hide yes)
			(effects
				(font
					(size 1.27 1.27)
				)
			)
		)
		(property "Value" ""
			(at 0 0 90)
			(layer "F.Fab")
			(effects
				(font
					(size 1.27 1.27)
				)
			)
		)
		(duplicate_pad_numbers_are_jumpers no)
		(fp_line
			(start 0.7874 -0.4064)
			(end 0.7874 0.4064)
			(stroke
				(width 0.1524)
				(type default)
			)
			(layer "F.SilkS")
		)
		(fp_line
			(start -0.7874 -0.4064)
			(end 0.7874 -0.4064)
			(stroke
				(width 0.1524)
				(type default)
			)
			(layer "F.SilkS")
		)
		(fp_line
			(start 0.7874 0.4064)
			(end -0.7874 0.4064)
			(stroke
				(width 0.1524)
				(type default)
			)
			(layer "F.SilkS")
		)
		(fp_line
			(start -0.7874 0.4064)
			(end -0.7874 -0.4064)
			(stroke
				(width 0.1524)
				(type default)
			)
			(layer "F.SilkS")
		)
		(fp_line
			(start -0.12065 -0.305054)
			(end -0.12065 -0.2794)
			(stroke
				(width 0.1)
				(type default)
			)
			(layer "F.Fab")
		)
		(fp_line
			(start -0.67945 -0.305054)
			(end -0.12065 -0.305054)
			(stroke
				(width 0.1)
				(type default)
			)
			(layer "F.Fab")
		)
		(fp_line
			(start 0.67945 -0.3048)
			(end 0.67945 0.3048)
			(stroke
				(width 0.1)
				(type default)
			)
			(layer "F.Fab")
		)
		(fp_line
			(start 0.12065 -0.3048)
			(end 0.67945 -0.3048)
			(stroke
				(width 0.1)
				(type default)
			)
			(layer "F.Fab")
		)
		(fp_line
			(start 0.12065 -0.2794)
			(end 0.12065 -0.3048)
			(stroke
				(width 0.1)
				(type default)
			)
			(layer "F.Fab")
		)
		(fp_line
			(start -0.12065 -0.2794)
			(end 0.12065 -0.2794)
			(stroke
				(width 0.1)
				(type default)
			)
			(layer "F.Fab")
		)
		(fp_line
			(start 0.120396 0.2794)
			(end -0.12065 0.2794)
			(stroke
				(width 0.1)
				(type default)
			)
			(layer "F.Fab")
		)
		(fp_line
			(start -0.12065 0.2794)
			(end -0.12065 0.3048)
			(stroke
				(width 0.1)
				(type default)
			)
			(layer "F.Fab")
		)
		(fp_line
			(start 0.67945 0.3048)
			(end 0.120396 0.3048)
			(stroke
				(width 0.1)
				(type default)
			)
			(layer "F.Fab")
		)
		(fp_line
			(start 0.120396 0.3048)
			(end 0.120396 0.2794)
			(stroke
				(width 0.1)
				(type default)
			)
			(layer "F.Fab")
		)
		(fp_line
			(start -0.12065 0.3048)
			(end -0.67945 0.3048)
			(stroke
				(width 0.1)
				(type default)
			)
			(layer "F.Fab")
		)
		(fp_line
			(start -0.67945 0.3048)
			(end -0.67945 -0.305054)
			(stroke
				(width 0.1)
				(type default)
			)
			(layer "F.Fab")
		)
		(pad "1" smd circle
			(at -0.40005 0 90)
			(size 0 0)
			(layers "F.Cu" "F.Mask" "F.Paste")
			(net "P3V3_OCP_SFF_R")
		)
		(pad "2" smd circle
			(at 0.40005 0 90)
			(size 0 0)
			(layers "F.Cu" "F.Mask" "F.Paste")
			(net "P3V3_OCP_GATE_PU202_1")
		)
	)
)
